# BASEBOARD_FAB2 (Tioga Pass) — schematic netlist excerpt (pin names and nets, part order shuffled) for the footprints in the layout excerpt that follows; sources: Cadence DE-HDL packaged netlist, KiCad conversion of Wiwynn_Tioga_Pass_MB.brd

C25W73  CAP  12.0PF 50V 5% COG  pkg 0402LF  page 252 : A = BMC_VGA_GREEN ; B = GND
R25W130  RES  4.75K 1% CHIP  pkg 0402  page 146 : A = P3V3 ; B = I2C_BMC_VGA_DDC_SDA
R1M17  RES  0.0 5% CHIP  pkg 0402  page 186 : A = RMII_BMC_OCP_RXD0 ; B = RMII_BMC_OCP_RXD0_R

(kicad_pcb
	(version 20260206)
	(generator "pcbnew")
	(generator_version "10.0")
	(general
		(thickness 1.6)
		(legacy_teardrops no)
	)
	(paper "A4")
	(title_block
		(title "Wiwynn_Tioga_Pass_MB.brd")
		(comment 1 "Tioga Pass / footprints 4460-4462 of 4770")
	)
	(layers
		(0 "F.Cu" signal "TOP")
		(4 "In1.Cu" signal "L2GND")
		(6 "In2.Cu" signal "L3")
		(8 "In3.Cu" signal "L4GND")
		(10 "In4.Cu" signal "L5")
		(12 "In5.Cu" signal "L6GND")
		(14 "In6.Cu" signal "L7VCC")
		(16 "In7.Cu" signal "L8VCC")
		(18 "In8.Cu" signal "L9GND")
		(20 "In9.Cu" signal "L10")
		(22 "In10.Cu" signal "L11GND")
		(24 "In11.Cu" signal "L12")
		(26 "In12.Cu" signal "L13GND")
		(2 "B.Cu" signal "BOTTOM")
		(9 "F.Adhes" user "F.Adhesive")
		(11 "B.Adhes" user "B.Adhesive")
		(13 "F.Paste" user "Package Geometry/Pastemask Top")
		(15 "B.Paste" user "Package Geometry/Pastemask Bottom")
		(5 "F.SilkS" user "Ref Des/Silkscreen Top")
		(7 "B.SilkS" user "Ref Des/Silkscreen Bottom")
		(1 "F.Mask" user "Board Geometry/Soldermask Top")
		(3 "B.Mask" user "Board Geometry/Soldermask Bottom")
		(17 "Dwgs.User" user "User.Drawings")
		(19 "Cmts.User" user "User.Comments")
		(21 "Eco1.User" user "User.Eco1")
		(23 "Eco2.User" user "User.Eco2")
		(25 "Edge.Cuts" user "Board Geometry/Outline")
		(27 "Margin" user)
		(31 "F.CrtYd" user "Package Geometry/Place Bound Top")
		(29 "B.CrtYd" user "Package Geometry/Place Bound Bottom")
		(35 "F.Fab" user "Ref Des/Assembly Top")
		(33 "B.Fab" user "Ref Des/Assembly Bottom")
	)
	(footprint ""
		(layer "B.Cu")
		(at 428.3075 -22.606 -90)
		(property "Reference" "R25W130"
			(at 0.8382 -0.67818 270)
			(unlocked yes)
			(layer "B.SilkS")
			(effects
				(font
					(size 0.4064 0.254)
					(thickness 0.1524)
				)
				(justify left mirror)
			)
		)
		(property "Value" ""
			(at 0 0 90)
			(layer "B.Fab")
			(effects
				(font
					(size 1.27 1.27)
				)
				(justify mirror)
			)
		)
		(duplicate_pad_numbers_are_jumpers no)
		(fp_poly
			(pts
				(xy 0.2794 -0.1016) (xy -0.2794 -0.1016) (xy -0.2794 0.9906) (xy 0.2794 0.9906)
			)
			(stroke
				(width 0)
				(type default)
			)
			(fill no)
			(layer "B.CrtYd")
		)
		(fp_line
			(start -0.2794 0.9906)
			(end -0.2794 -0.1016)
			(stroke
				(width 0.1)
				(type default)
			)
			(layer "B.Fab")
		)
		(fp_line
			(start 0.2794 0.9906)
			(end -0.2794 0.9906)
			(stroke
				(width 0.1)
				(type default)
			)
			(layer "B.Fab")
		)
		(fp_line
			(start -0.2794 -0.1016)
			(end 0.2794 -0.1016)
			(stroke
				(width 0.1)
				(type default)
			)
			(layer "B.Fab")
		)
		(fp_line
			(start 0.2794 -0.1016)
			(end 0.2794 0.9906)
			(stroke
				(width 0.1)
				(type default)
			)
			(layer "B.Fab")
		)
		(pad "1" smd rect
			(at 0 0 90)
			(size 0.508 0.508)
			(layers "B.Cu" "B.Mask" "B.Paste")
			(net "P3V3")
		)
		(pad "2" smd rect
			(at 0 0.889 90)
			(size 0.508 0.508)
			(layers "B.Cu" "B.Mask" "B.Paste")
			(net "I2C_BMC_VGA_DDC_SDA")
		)
		(zone
			(layer "B.Cu")
			(hatch none 0.5)
			(connect_pads
				(clearance 0)
			)
			(min_thickness 0.25)
			(keepout
				(tracks not_allowed)
				(vias allowed)
				(pads allowed)
				(copperpour not_allowed)
				(footprints allowed)
			)
			(placement
				(enabled no)
				(sheetname "")
			)
			(fill
				(thermal_gap 0.5)
				(thermal_bridge_width 0.5)
				(island_removal_mode 0)
			)
			(polygon
				(pts
					(xy 427.6725 -22.352) (xy 427.6725 -22.86) (xy 428.0535 -22.86) (xy 428.0535 -22.352)
				)
			)
		)
		(zone
			(layer "B.Cu")
			(hatch none 0.5)
			(connect_pads
				(clearance 0)
			)
			(min_thickness 0.25)
			(keepout
				(tracks allowed)
				(vias not_allowed)
				(pads allowed)
				(copperpour not_allowed)
				(footprints allowed)
			)
			(placement
				(enabled no)
				(sheetname "")
			)
			(fill
				(thermal_gap 0.5)
				(thermal_bridge_width 0.5)
				(island_removal_mode 0)
			)
			(polygon
				(pts
					(xy 428.0535 -22.352) (xy 428.0535 -22.86) (xy 427.6725 -22.86) (xy 427.6725 -22.352)
				)
			)
		)
	)
	(footprint ""
		(layer "B.Cu")
		(at 471.424 -116.84 180)
		(property "Reference" "R1M17"
			(at 0 0 0)
			(layer "B.SilkS")
			(hide yes)
			(effects
				(font
					(size 1.27 1.27)
				)
				(justify mirror)
			)
		)
		(property "Value" ""
			(at 0 0 0)
			(layer "B.Fab")
			(effects
				(font
					(size 1.27 1.27)
				)
				(justify mirror)
			)
		)
		(duplicate_pad_numbers_are_jumpers no)
		(fp_poly
			(pts
				(xy 0.2794 -0.1016) (xy -0.2794 -0.1016) (xy -0.2794 0.9906) (xy 0.2794 0.9906)
			)
			(stroke
				(width 0)
				(type default)
			)
			(fill no)
			(layer "B.CrtYd")
		)
		(fp_line
			(start 0.2794 0.9906)
			(end -0.2794 0.9906)
			(stroke
				(width 0.1)
				(type default)
			)
			(layer "B.Fab")
		)
		(fp_line
			(start 0.2794 -0.1016)
			(end 0.2794 0.9906)
			(stroke
				(width 0.1)
				(type default)
			)
			(layer "B.Fab")
		)
		(fp_line
			(start -0.2794 0.9906)
			(end -0.2794 -0.1016)
			(stroke
				(width 0.1)
				(type default)
			)
			(layer "B.Fab")
		)
		(fp_line
			(start -0.2794 -0.1016)
			(end 0.2794 -0.1016)
			(stroke
				(width 0.1)
				(type default)
			)
			(layer "B.Fab")
		)
		(pad "1" smd rect
			(at 0 0)
			(size 0.508 0.508)
			(layers "B.Cu" "B.Mask" "B.Paste")
			(net "RMII_BMC_OCP_RXD0")
		)
		(pad "2" smd rect
			(at 0 0.889)
			(size 0.508 0.508)
			(layers "B.Cu" "B.Mask" "B.Paste")
			(net "RMII_BMC_OCP_RXD0_R")
		)
		(zone
			(layer "B.Cu")
			(hatch none 0.5)
			(connect_pads
				(clearance 0)
			)
			(min_thickness 0.25)
			(keepout
				(tracks not_allowed)
				(vias allowed)
				(pads allowed)
				(copperpour not_allowed)
				(footprints allowed)
			)
			(placement
				(enabled no)
				(sheetname "")
			)
			(fill
				(thermal_gap 0.5)
				(thermal_bridge_width 0.5)
				(island_removal_mode 0)
			)
			(polygon
				(pts
					(xy 471.17 -117.475) (xy 471.678 -117.475) (xy 471.678 -117.094) (xy 471.17 -117.094)
				)
			)
		)
		(zone
			(layer "B.Cu")
			(hatch none 0.5)
			(connect_pads
				(clearance 0)
			)
			(min_thickness 0.25)
			(keepout
				(tracks allowed)
				(vias not_allowed)
				(pads allowed)
				(copperpour not_allowed)
				(footprints allowed)
			)
			(placement
				(enabled no)
				(sheetname "")
			)
			(fill
				(thermal_gap 0.5)
				(thermal_bridge_width 0.5)
				(island_removal_mode 0)
			)
			(polygon
				(pts
					(xy 471.17 -117.094) (xy 471.678 -117.094) (xy 471.678 -117.475) (xy 471.17 -117.475)
				)
			)
		)
	)
	(footprint ""
		(layer "B.Cu")
		(at 416.179 -22.987 180)
		(property "Reference" "C25W73"
			(at 0.8382 -0.67818 180)
			(unlocked yes)
			(layer "B.SilkS")
			(effects
				(font
					(size 0.4064 0.254)
					(thickness 0.1524)
				)
				(justify left mirror)
			)
		)
		(property "Value" ""
			(at 0 0 0)
			(layer "B.Fab")
			(effects
				(font
					(size 1.27 1.27)
				)
				(justify mirror)
			)
		)
		(duplicate_pad_numbers_are_jumpers no)
		(fp_poly
			(pts
				(xy -0.3048 -0.1016) (xy -0.3048 0.9906) (xy 0.3048 0.9906) (xy 0.3048 -0.1016)
			)
			(stroke
				(width 0)
				(type default)
			)
			(fill no)
			(layer "B.CrtYd")
		)
		(fp_line
			(start 0.3048 0.9906)
			(end -0.3048 0.9906)
			(stroke
				(width 0.1)
				(type default)
			)
			(layer "B.Fab")
		)
		(fp_line
			(start 0.3048 -0.1016)
			(end 0.3048 0.9906)
			(stroke
				(width 0.1)
				(type default)
			)
			(layer "B.Fab")
		)
		(fp_line
			(start -0.3048 0.9906)
			(end -0.3048 -0.1016)
			(stroke
				(width 0.1)
				(type default)
			)
			(layer "B.Fab")
		)
		(fp_line
			(start -0.3048 -0.1016)
			(end 0.3048 -0.1016)
			(stroke
				(width 0.1)
				(type default)
			)
			(layer "B.Fab")
		)
		(pad "1" smd rect
			(at 0 0)
			(size 0.508 0.508)
			(layers "B.Cu" "B.Mask" "B.Paste")
			(net "BMC_VGA_GREEN")
		)
		(pad "2" smd rect
			(at 0 0.889)
			(size 0.508 0.508)
			(layers "B.Cu" "B.Mask" "B.Paste")
			(net "GND")
		)
		(zone
			(layer "B.Cu")
			(hatch none 0.5)
			(connect_pads
				(clearance 0)
			)
			(min_thickness 0.25)
			(keepout
				(tracks not_allowed)
				(vias allowed)
				(pads allowed)
				(copperpour not_allowed)
				(footprints allowed)
			)
			(placement
				(enabled no)
				(sheetname "")
			)
			(fill
				(thermal_gap 0.5)
				(thermal_bridge_width 0.5)
				(island_removal_mode 0)
			)
			(polygon
				(pts
					(xy 415.925 -23.622) (xy 416.433 -23.622) (xy 416.433 -23.241) (xy 415.925 -23.241)
				)
			)
		)
		(zone
			(layer "B.Cu")
			(hatch none 0.5)
			(connect_pads
				(clearance 0)
			)
			(min_thickness 0.25)
			(keepout
				(tracks allowed)
				(vias not_allowed)
				(pads allowed)
				(copperpour not_allowed)
				(footprints allowed)
			)
			(placement
				(enabled no)
				(sheetname "")
			)
			(fill
				(thermal_gap 0.5)
				(thermal_bridge_width 0.5)
				(island_removal_mode 0)
			)
			(polygon
				(pts
					(xy 415.925 -23.241) (xy 416.433 -23.241) (xy 416.433 -23.622) (xy 415.925 -23.622)
				)
			)
		)
	)
)
